(kicad_pcb
	(version 20260206)
	(generator "pcbnew")
	(generator_version "10.0")
	(general
		(thickness 1.6)
		(legacy_teardrops no)
	)
	(paper "A4")
	(title_block
		(title "15969-1a.1015WZS0858.brd")
		(comment 1 "Tioga Pass / footprint 150 of 295 (SLOT3), pads 1-76 of 166")
	)
	(layers
		(0 "F.Cu" signal "TOP")
		(4 "In1.Cu" signal "L2GND")
		(6 "In2.Cu" signal "L3")
		(8 "In3.Cu" signal "L4")
		(10 "In4.Cu" signal "L5GND")
		(2 "B.Cu" signal "BOTTOM")
		(9 "F.Adhes" user "F.Adhesive")
		(11 "B.Adhes" user "B.Adhesive")
		(13 "F.Paste" user "Package Geometry/Pastemask Top")
		(15 "B.Paste" user "Package Geometry/Pastemask Bottom")
		(5 "F.SilkS" user "Ref Des/Silkscreen Top")
		(7 "B.SilkS" user "Ref Des/Silkscreen Bottom")
		(1 "F.Mask" user "Board Geometry/Soldermask Top")
		(3 "B.Mask" user "Board Geometry/Soldermask Bottom")
		(17 "Dwgs.User" user "User.Drawings")
		(19 "Cmts.User" user "User.Comments")
		(21 "Eco1.User" user "User.Eco1")
		(23 "Eco2.User" user "User.Eco2")
		(25 "Edge.Cuts" user "Board Geometry/Outline")
		(27 "Margin" user)
		(31 "F.CrtYd" user "Package Geometry/Place Bound Top")
		(29 "B.CrtYd" user "Package Geometry/Place Bound Bottom")
		(35 "F.Fab" user "Ref Des/Assembly Top")
		(33 "B.Fab" user "Ref Des/Assembly Bottom")
	)
	(footprint ""
		(layer "F.Cu")
		(at 42.729912 -30.820106)
		(property "Reference" "SLOT3"
			(at 0 0 0)
			(layer "F.SilkS")
			(hide yes)
			(effects
				(font
					(size 1.27 1.27)
				)
			)
		)
		(property "Value" "PCISLT164-129-GP"
			(at -15.9639 4.8514 0)
			(unlocked yes)
			(layer "F.Fab")
			(hide yes)
			(effects
				(font
					(size 1.016 1.016)
					(thickness 0.1524)
				)
			)
		)
		(property "Device Type" "10018783-10203TLF"
			(at -15.9639 3.3274 0)
			(unlocked yes)
			(layer "F.Fab")
			(hide yes)
			(effects
				(font
					(size 1.016 1.016)
					(thickness 0.1524)
				)
			)
		)
		(duplicate_pad_numbers_are_jumpers no)
		(pad "" np_thru_hole circle
			(at 0 0)
			(size 0.254 0.254)
			(drill 2.3622)
			(layers "*.Cu" "*.Mask")
			(clearance 1.4097)
			(thermal_gap 1.4097)
		)
		(pad "" np_thru_hole circle
			(at 73.14946 0)
			(size 0.254 0.254)
			(drill 2.3622)
			(layers "*.Cu" "*.Mask")
			(clearance 1.4097)
			(thermal_gap 1.4097)
		)
		(pad "A1" thru_hole circle
			(at -11.64971 -1.24968)
			(size 1.0668 1.0668)
			(drill 0.7112)
			(layers "*.Cu" "*.Mask")
			(remove_unused_layers no)
			(net "PD_SLOT3_PRSNT1")
			(clearance 0.1778)
			(thermal_gap 0.1778)
		)
		(pad "A2" thru_hole circle
			(at -10.65022 -3.24993)
			(size 1.0668 1.0668)
			(drill 0.7112)
			(layers "*.Cu" "*.Mask")
			(remove_unused_layers no)
			(net "P12V_SLOT3")
			(clearance 0.1778)
			(thermal_gap 0.1778)
		)
		(pad "A3" thru_hole circle
			(at -9.64946 -1.24968)
			(size 1.0668 1.0668)
			(drill 0.7112)
			(layers "*.Cu" "*.Mask")
			(remove_unused_layers no)
			(net "P12V_SLOT3")
			(clearance 0.1778)
			(thermal_gap 0.1778)
		)
		(pad "A4" thru_hole circle
			(at -8.64997 -3.24993)
			(size 1.0668 1.0668)
			(drill 0.7112)
			(layers "*.Cu" "*.Mask")
			(remove_unused_layers no)
			(net "GND")
			(clearance 0.1778)
			(thermal_gap 0.1778)
		)
		(pad "A5" thru_hole circle
			(at -7.65048 -1.24968)
			(size 1.0668 1.0668)
			(drill 0.7112)
			(layers "*.Cu" "*.Mask")
			(remove_unused_layers no)
			(net "Net_95")
			(clearance 0.1778)
			(thermal_gap 0.1778)
		)
		(pad "A6" thru_hole circle
			(at -6.64972 -3.24993)
			(size 1.0668 1.0668)
			(drill 0.7112)
			(layers "*.Cu" "*.Mask")
			(remove_unused_layers no)
			(net "Net_96")
			(clearance 0.1778)
			(thermal_gap 0.1778)
		)
		(pad "A7" thru_hole circle
			(at -5.65023 -1.24968)
			(size 1.0668 1.0668)
			(drill 0.7112)
			(layers "*.Cu" "*.Mask")
			(remove_unused_layers no)
			(net "SMCLK_PCH_SLOT3_R")
			(clearance 0.1778)
			(thermal_gap 0.1778)
		)
		(pad "A8" thru_hole circle
			(at -4.64947 -3.24993)
			(size 1.0668 1.0668)
			(drill 0.7112)
			(layers "*.Cu" "*.Mask")
			(remove_unused_layers no)
			(net "SMDAT_PCH_SLOT3_R")
			(clearance 0.1778)
			(thermal_gap 0.1778)
		)
		(pad "A9" thru_hole circle
			(at -3.64998 -1.24968)
			(size 1.0668 1.0668)
			(drill 0.7112)
			(layers "*.Cu" "*.Mask")
			(remove_unused_layers no)
			(net "P3V3")
			(clearance 0.1778)
			(thermal_gap 0.1778)
		)
		(pad "A10" thru_hole circle
			(at -2.65049 -3.24993)
			(size 1.0668 1.0668)
			(drill 0.7112)
			(layers "*.Cu" "*.Mask")
			(remove_unused_layers no)
			(net "P3V3")
			(clearance 0.1778)
			(thermal_gap 0.1778)
		)
		(pad "A11" thru_hole circle
			(at -1.64973 -1.24968)
			(size 1.0668 1.0668)
			(drill 0.7112)
			(layers "*.Cu" "*.Mask")
			(remove_unused_layers no)
			(net "RESET_BUF_N_SLOT3")
			(clearance 0.1778)
			(thermal_gap 0.1778)
		)
		(pad "A12" thru_hole circle
			(at 1.35001 -3.24993)
			(size 1.0668 1.0668)
			(drill 0.7112)
			(layers "*.Cu" "*.Mask")
			(remove_unused_layers no)
			(net "GND")
			(clearance 0.1778)
			(thermal_gap 0.1778)
		)
		(pad "A13" thru_hole circle
			(at 2.3495 -1.24968)
			(size 1.0668 1.0668)
			(drill 0.7112)
			(layers "*.Cu" "*.Mask")
			(remove_unused_layers no)
			(net "CLK_100M_PCH_SLOTX24_S4_DP")
			(clearance 0.1778)
			(thermal_gap 0.1778)
		)
		(pad "A14" thru_hole circle
			(at 3.35026 -3.24993)
			(size 1.0668 1.0668)
			(drill 0.7112)
			(layers "*.Cu" "*.Mask")
			(remove_unused_layers no)
			(net "CLK_100M_PCH_SLOTX24_S4_DN")
			(clearance 0.1778)
			(thermal_gap 0.1778)
		)
		(pad "A15" thru_hole circle
			(at 4.34975 -1.24968)
			(size 1.0668 1.0668)
			(drill 0.7112)
			(layers "*.Cu" "*.Mask")
			(remove_unused_layers no)
			(net "GND")
			(clearance 0.1778)
			(thermal_gap 0.1778)
		)
		(pad "A16" thru_hole circle
			(at 5.35051 -3.24993)
			(size 1.0668 1.0668)
			(drill 0.7112)
			(layers "*.Cu" "*.Mask")
			(remove_unused_layers no)
			(net "P3E_CPU0_PE2_SS_RXP<0>")
			(clearance 0.1778)
			(thermal_gap 0.1778)
		)
		(pad "A17" thru_hole circle
			(at 6.35 -1.24968)
			(size 1.0668 1.0668)
			(drill 0.7112)
			(layers "*.Cu" "*.Mask")
			(remove_unused_layers no)
			(net "P3E_CPU0_PE2_SS_RXN<0>")
			(clearance 0.1778)
			(thermal_gap 0.1778)
		)
		(pad "A18" thru_hole circle
			(at 7.34949 -3.24993)
			(size 1.0668 1.0668)
			(drill 0.7112)
			(layers "*.Cu" "*.Mask")
			(remove_unused_layers no)
			(net "GND")
			(clearance 0.1778)
			(thermal_gap 0.1778)
		)
		(pad "A19" thru_hole circle
			(at 8.35025 -1.24968)
			(size 1.0668 1.0668)
			(drill 0.7112)
			(layers "*.Cu" "*.Mask")
			(remove_unused_layers no)
			(net "Net_92")
			(clearance 0.1778)
			(thermal_gap 0.1778)
		)
		(pad "A20" thru_hole circle
			(at 9.34974 -3.24993)
			(size 1.0668 1.0668)
			(drill 0.7112)
			(layers "*.Cu" "*.Mask")
			(remove_unused_layers no)
			(net "GND")
			(clearance 0.1778)
			(thermal_gap 0.1778)
		)
		(pad "A21" thru_hole circle
			(at 10.3505 -1.24968)
			(size 1.0668 1.0668)
			(drill 0.7112)
			(layers "*.Cu" "*.Mask")
			(remove_unused_layers no)
			(net "P3E_CPU0_PE2_SS_RXP<1>")
			(clearance 0.1778)
			(thermal_gap 0.1778)
		)
		(pad "A22" thru_hole circle
			(at 11.34999 -3.24993)
			(size 1.0668 1.0668)
			(drill 0.7112)
			(layers "*.Cu" "*.Mask")
			(remove_unused_layers no)
			(net "P3E_CPU0_PE2_SS_RXN<1>")
			(clearance 0.1778)
			(thermal_gap 0.1778)
		)
		(pad "A23" thru_hole circle
			(at 12.34948 -1.24968)
			(size 1.0668 1.0668)
			(drill 0.7112)
			(layers "*.Cu" "*.Mask")
			(remove_unused_layers no)
			(net "GND")
			(clearance 0.1778)
			(thermal_gap 0.1778)
		)
		(pad "A24" thru_hole circle
			(at 13.35024 -3.24993)
			(size 1.0668 1.0668)
			(drill 0.7112)
			(layers "*.Cu" "*.Mask")
			(remove_unused_layers no)
			(net "GND")
			(clearance 0.1778)
			(thermal_gap 0.1778)
		)
		(pad "A25" thru_hole circle
			(at 14.34973 -1.24968)
			(size 1.0668 1.0668)
			(drill 0.7112)
			(layers "*.Cu" "*.Mask")
			(remove_unused_layers no)
			(net "P3E_CPU0_PE2_SS_RXP<2>")
			(clearance 0.1778)
			(thermal_gap 0.1778)
		)
		(pad "A26" thru_hole circle
			(at 15.35049 -3.24993)
			(size 1.0668 1.0668)
			(drill 0.7112)
			(layers "*.Cu" "*.Mask")
			(remove_unused_layers no)
			(net "P3E_CPU0_PE2_SS_RXN<2>")
			(clearance 0.1778)
			(thermal_gap 0.1778)
		)
		(pad "A27" thru_hole circle
			(at 16.34998 -1.24968)
			(size 1.0668 1.0668)
			(drill 0.7112)
			(layers "*.Cu" "*.Mask")
			(remove_unused_layers no)
			(net "GND")
			(clearance 0.1778)
			(thermal_gap 0.1778)
		)
		(pad "A28" thru_hole circle
			(at 17.34947 -3.24993)
			(size 1.0668 1.0668)
			(drill 0.7112)
			(layers "*.Cu" "*.Mask")
			(remove_unused_layers no)
			(net "GND")
			(clearance 0.1778)
			(thermal_gap 0.1778)
		)
		(pad "A29" thru_hole circle
			(at 18.35023 -1.24968)
			(size 1.0668 1.0668)
			(drill 0.7112)
			(layers "*.Cu" "*.Mask")
			(remove_unused_layers no)
			(net "P3E_CPU0_PE2_SS_RXP<3>")
			(clearance 0.1778)
			(thermal_gap 0.1778)
		)
		(pad "A30" thru_hole circle
			(at 19.34972 -3.24993)
			(size 1.0668 1.0668)
			(drill 0.7112)
			(layers "*.Cu" "*.Mask")
			(remove_unused_layers no)
			(net "P3E_CPU0_PE2_SS_RXN<3>")
			(clearance 0.1778)
			(thermal_gap 0.1778)
		)
		(pad "A31" thru_hole circle
			(at 20.35048 -1.24968)
			(size 1.0668 1.0668)
			(drill 0.7112)
			(layers "*.Cu" "*.Mask")
			(remove_unused_layers no)
			(net "GND")
			(clearance 0.1778)
			(thermal_gap 0.1778)
		)
		(pad "A32" thru_hole circle
			(at 21.34997 -3.24993)
			(size 1.0668 1.0668)
			(drill 0.7112)
			(layers "*.Cu" "*.Mask")
			(remove_unused_layers no)
			(net "USB_HUB_PCIE_DP1")
			(clearance 0.1778)
			(thermal_gap 0.1778)
		)
		(pad "A33" thru_hole circle
			(at 22.34946 -1.24968)
			(size 1.0668 1.0668)
			(drill 0.7112)
			(layers "*.Cu" "*.Mask")
			(remove_unused_layers no)
			(net "USB_HUB_PCIE_DN1")
			(clearance 0.1778)
			(thermal_gap 0.1778)
		)
		(pad "A34" thru_hole circle
			(at 23.35022 -3.24993)
			(size 1.0668 1.0668)
			(drill 0.7112)
			(layers "*.Cu" "*.Mask")
			(remove_unused_layers no)
			(net "GND")
			(clearance 0.1778)
			(thermal_gap 0.1778)
		)
		(pad "A35" thru_hole circle
			(at 24.34971 -1.24968)
			(size 1.0668 1.0668)
			(drill 0.7112)
			(layers "*.Cu" "*.Mask")
			(remove_unused_layers no)
			(net "P3E_CPU0_PE2_SS_RXP<4>")
			(clearance 0.1778)
			(thermal_gap 0.1778)
		)
		(pad "A36" thru_hole circle
			(at 25.35047 -3.24993)
			(size 1.0668 1.0668)
			(drill 0.7112)
			(layers "*.Cu" "*.Mask")
			(remove_unused_layers no)
			(net "P3E_CPU0_PE2_SS_RXN<4>")
			(clearance 0.1778)
			(thermal_gap 0.1778)
		)
		(pad "A37" thru_hole circle
			(at 26.34996 -1.24968)
			(size 1.0668 1.0668)
			(drill 0.7112)
			(layers "*.Cu" "*.Mask")
			(remove_unused_layers no)
			(net "GND")
			(clearance 0.1778)
			(thermal_gap 0.1778)
		)
		(pad "A38" thru_hole circle
			(at 27.34945 -3.24993)
			(size 1.0668 1.0668)
			(drill 0.7112)
			(layers "*.Cu" "*.Mask")
			(remove_unused_layers no)
			(net "GND")
			(clearance 0.1778)
			(thermal_gap 0.1778)
		)
		(pad "A39" thru_hole circle
			(at 28.35021 -1.24968)
			(size 1.0668 1.0668)
			(drill 0.7112)
			(layers "*.Cu" "*.Mask")
			(remove_unused_layers no)
			(net "P3E_CPU0_PE2_SS_RXP<5>")
			(clearance 0.1778)
			(thermal_gap 0.1778)
		)
		(pad "A40" thru_hole circle
			(at 29.3497 -3.24993)
			(size 1.0668 1.0668)
			(drill 0.7112)
			(layers "*.Cu" "*.Mask")
			(remove_unused_layers no)
			(net "P3E_CPU0_PE2_SS_RXN<5>")
			(clearance 0.1778)
			(thermal_gap 0.1778)
		)
		(pad "A41" thru_hole circle
			(at 30.35046 -1.24968)
			(size 1.0668 1.0668)
			(drill 0.7112)
			(layers "*.Cu" "*.Mask")
			(remove_unused_layers no)
			(net "GND")
			(clearance 0.1778)
			(thermal_gap 0.1778)
		)
		(pad "A42" thru_hole circle
			(at 31.34995 -3.24993)
			(size 1.0668 1.0668)
			(drill 0.7112)
			(layers "*.Cu" "*.Mask")
			(remove_unused_layers no)
			(net "GND")
			(clearance 0.1778)
			(thermal_gap 0.1778)
		)
		(pad "A43" thru_hole circle
			(at 32.34944 -1.24968)
			(size 1.0668 1.0668)
			(drill 0.7112)
			(layers "*.Cu" "*.Mask")
			(remove_unused_layers no)
			(net "P3E_CPU0_PE2_SS_RXP<6>")
			(clearance 0.1778)
			(thermal_gap 0.1778)
		)
		(pad "A44" thru_hole circle
			(at 33.3502 -3.24993)
			(size 1.0668 1.0668)
			(drill 0.7112)
			(layers "*.Cu" "*.Mask")
			(remove_unused_layers no)
			(net "P3E_CPU0_PE2_SS_RXN<6>")
			(clearance 0.1778)
			(thermal_gap 0.1778)
		)
		(pad "A45" thru_hole circle
			(at 34.34969 -1.24968)
			(size 1.0668 1.0668)
			(drill 0.7112)
			(layers "*.Cu" "*.Mask")
			(remove_unused_layers no)
			(net "GND")
			(clearance 0.1778)
			(thermal_gap 0.1778)
		)
		(pad "A46" thru_hole circle
			(at 35.35045 -3.24993)
			(size 1.0668 1.0668)
			(drill 0.7112)
			(layers "*.Cu" "*.Mask")
			(remove_unused_layers no)
			(net "GND")
			(clearance 0.1778)
			(thermal_gap 0.1778)
		)
		(pad "A47" thru_hole circle
			(at 36.34994 -1.24968)
			(size 1.0668 1.0668)
			(drill 0.7112)
			(layers "*.Cu" "*.Mask")
			(remove_unused_layers no)
			(net "P3E_CPU0_PE2_SS_RXP<7>")
			(clearance 0.1778)
			(thermal_gap 0.1778)
		)
		(pad "A48" thru_hole circle
			(at 37.34943 -3.24993)
			(size 1.0668 1.0668)
			(drill 0.7112)
			(layers "*.Cu" "*.Mask")
			(remove_unused_layers no)
			(net "P3E_CPU0_PE2_SS_RXN<7>")
			(clearance 0.1778)
			(thermal_gap 0.1778)
		)
		(pad "A49" thru_hole circle
			(at 38.35019 -1.24968)
			(size 1.0668 1.0668)
			(drill 0.7112)
			(layers "*.Cu" "*.Mask")
			(remove_unused_layers no)
			(net "GND")
			(clearance 0.1778)
			(thermal_gap 0.1778)
		)
		(pad "A50" thru_hole circle
			(at 39.34968 -3.24993)
			(size 1.0668 1.0668)
			(drill 0.7112)
			(layers "*.Cu" "*.Mask")
			(remove_unused_layers no)
			(net "Net_91")
			(clearance 0.1778)
			(thermal_gap 0.1778)
		)
		(pad "A51" thru_hole circle
			(at 40.35044 -1.24968)
			(size 1.0668 1.0668)
			(drill 0.7112)
			(layers "*.Cu" "*.Mask")
			(remove_unused_layers no)
			(net "GND")
			(clearance 0.1778)
			(thermal_gap 0.1778)
		)
		(pad "A52" thru_hole circle
			(at 41.34993 -3.24993)
			(size 1.0668 1.0668)
			(drill 0.7112)
			(layers "*.Cu" "*.Mask")
			(remove_unused_layers no)
			(net "P3E_CPU0_PE2_SS_RXP<8>")
			(clearance 0.1778)
			(thermal_gap 0.1778)
		)
		(pad "A53" thru_hole circle
			(at 42.34942 -1.24968)
			(size 1.0668 1.0668)
			(drill 0.7112)
			(layers "*.Cu" "*.Mask")
			(remove_unused_layers no)
			(net "P3E_CPU0_PE2_SS_RXN<8>")
			(clearance 0.1778)
			(thermal_gap 0.1778)
		)
		(pad "A54" thru_hole circle
			(at 43.35018 -3.24993)
			(size 1.0668 1.0668)
			(drill 0.7112)
			(layers "*.Cu" "*.Mask")
			(remove_unused_layers no)
			(net "GND")
			(clearance 0.1778)
			(thermal_gap 0.1778)
		)
		(pad "A55" thru_hole circle
			(at 44.34967 -1.24968)
			(size 1.0668 1.0668)
			(drill 0.7112)
			(layers "*.Cu" "*.Mask")
			(remove_unused_layers no)
			(net "GND")
			(clearance 0.1778)
			(thermal_gap 0.1778)
		)
		(pad "A56" thru_hole circle
			(at 45.35043 -3.24993)
			(size 1.0668 1.0668)
			(drill 0.7112)
			(layers "*.Cu" "*.Mask")
			(remove_unused_layers no)
			(net "P3E_CPU0_PE2_SS_RXP<9>")
			(clearance 0.1778)
			(thermal_gap 0.1778)
		)
		(pad "A57" thru_hole circle
			(at 46.34992 -1.24968)
			(size 1.0668 1.0668)
			(drill 0.7112)
			(layers "*.Cu" "*.Mask")
			(remove_unused_layers no)
			(net "P3E_CPU0_PE2_SS_RXN<9>")
			(clearance 0.1778)
			(thermal_gap 0.1778)
		)
		(pad "A58" thru_hole circle
			(at 47.34941 -3.24993)
			(size 1.0668 1.0668)
			(drill 0.7112)
			(layers "*.Cu" "*.Mask")
			(remove_unused_layers no)
			(net "GND")
			(clearance 0.1778)
			(thermal_gap 0.1778)
		)
		(pad "A59" thru_hole circle
			(at 48.35017 -1.24968)
			(size 1.0668 1.0668)
			(drill 0.7112)
			(layers "*.Cu" "*.Mask")
			(remove_unused_layers no)
			(net "GND")
			(clearance 0.1778)
			(thermal_gap 0.1778)
		)
		(pad "A60" thru_hole circle
			(at 49.34966 -3.24993)
			(size 1.0668 1.0668)
			(drill 0.7112)
			(layers "*.Cu" "*.Mask")
			(remove_unused_layers no)
			(net "P3E_CPU0_PE2_SS_RXP<10>")
			(clearance 0.1778)
			(thermal_gap 0.1778)
		)
		(pad "A61" thru_hole circle
			(at 50.35042 -1.24968)
			(size 1.0668 1.0668)
			(drill 0.7112)
			(layers "*.Cu" "*.Mask")
			(remove_unused_layers no)
			(net "P3E_CPU0_PE2_SS_RXN<10>")
			(clearance 0.1778)
			(thermal_gap 0.1778)
		)
		(pad "A62" thru_hole circle
			(at 51.34991 -3.24993)
			(size 1.0668 1.0668)
			(drill 0.7112)
			(layers "*.Cu" "*.Mask")
			(remove_unused_layers no)
			(net "GND")
			(clearance 0.1778)
			(thermal_gap 0.1778)
		)
		(pad "A63" thru_hole circle
			(at 52.3494 -1.24968)
			(size 1.0668 1.0668)
			(drill 0.7112)
			(layers "*.Cu" "*.Mask")
			(remove_unused_layers no)
			(net "GND")
			(clearance 0.1778)
			(thermal_gap 0.1778)
		)
		(pad "A64" thru_hole circle
			(at 53.35016 -3.24993)
			(size 1.0668 1.0668)
			(drill 0.7112)
			(layers "*.Cu" "*.Mask")
			(remove_unused_layers no)
			(net "P3E_CPU0_PE2_SS_RXP<11>")
			(clearance 0.1778)
			(thermal_gap 0.1778)
		)
		(pad "A65" thru_hole circle
			(at 54.34965 -1.24968)
			(size 1.0668 1.0668)
			(drill 0.7112)
			(layers "*.Cu" "*.Mask")
			(remove_unused_layers no)
			(net "P3E_CPU0_PE2_SS_RXN<11>")
			(clearance 0.1778)
			(thermal_gap 0.1778)
		)
		(pad "A66" thru_hole circle
			(at 55.35041 -3.24993)
			(size 1.0668 1.0668)
			(drill 0.7112)
			(layers "*.Cu" "*.Mask")
			(remove_unused_layers no)
			(net "GND")
			(clearance 0.1778)
			(thermal_gap 0.1778)
		)
		(pad "A67" thru_hole circle
			(at 56.3499 -1.24968)
			(size 1.0668 1.0668)
			(drill 0.7112)
			(layers "*.Cu" "*.Mask")
			(remove_unused_layers no)
			(net "GND")
			(clearance 0.1778)
			(thermal_gap 0.1778)
		)
		(pad "A68" thru_hole circle
			(at 57.34939 -3.24993)
			(size 1.0668 1.0668)
			(drill 0.7112)
			(layers "*.Cu" "*.Mask")
			(remove_unused_layers no)
			(net "P3E_CPU0_PE2_SS_RXP<12>")
			(clearance 0.1778)
			(thermal_gap 0.1778)
		)
		(pad "A69" thru_hole circle
			(at 58.35015 -1.24968)
			(size 1.0668 1.0668)
			(drill 0.7112)
			(layers "*.Cu" "*.Mask")
			(remove_unused_layers no)
			(net "P3E_CPU0_PE2_SS_RXN<12>")
			(clearance 0.1778)
			(thermal_gap 0.1778)
		)
		(pad "A70" thru_hole circle
			(at 59.34964 -3.24993)
			(size 1.0668 1.0668)
			(drill 0.7112)
			(layers "*.Cu" "*.Mask")
			(remove_unused_layers no)
			(net "GND")
			(clearance 0.1778)
			(thermal_gap 0.1778)
		)
		(pad "A71" thru_hole circle
			(at 60.3504 -1.24968)
			(size 1.0668 1.0668)
			(drill 0.7112)
			(layers "*.Cu" "*.Mask")
			(remove_unused_layers no)
			(net "GND")
			(clearance 0.1778)
			(thermal_gap 0.1778)
		)
		(pad "A72" thru_hole circle
			(at 61.34989 -3.24993)
			(size 1.0668 1.0668)
			(drill 0.7112)
			(layers "*.Cu" "*.Mask")
			(remove_unused_layers no)
			(net "P3E_CPU0_PE2_SS_RXP<13>")
			(clearance 0.1778)
			(thermal_gap 0.1778)
		)
		(pad "A73" thru_hole circle
			(at 62.34938 -1.24968)
			(size 1.0668 1.0668)
			(drill 0.7112)
			(layers "*.Cu" "*.Mask")
			(remove_unused_layers no)
			(net "P3E_CPU0_PE2_SS_RXN<13>")
			(clearance 0.1778)
			(thermal_gap 0.1778)
		)
		(pad "A74" thru_hole circle
			(at 63.35014 -3.24993)
			(size 1.0668 1.0668)
			(drill 0.7112)
			(layers "*.Cu" "*.Mask")
			(remove_unused_layers no)
			(net "GND")
			(clearance 0.1778)
			(thermal_gap 0.1778)
		)
	)
)
